# BASEBOARD_FAB2 (Tioga Pass) — schematic netlist excerpt (pin names and nets, part order shuffled) for the footprints in the layout excerpt that follows; sources: Cadence DE-HDL packaged netlist, KiCad conversion of Wiwynn_Tioga_Pass_MB.brd

EU4D4  PXE1610B  IC  pkg QFN  page 201
  BPWM1  = VR_PVSA_CPU0_PWM
  APWM6  = NC
  APWM5  = VR_PVCCIN_CPU0_PWM5
  APWM4  = VR_PVCCIN_CPU0_PWM4
  APWM3  = VR_PVCCIN_CPU0_PWM3
  APWM2  = VR_PVCCIN_CPU0_PWM2
  APWM1  = VR_PVCCIN_CPU0_PWM1
  SDA  = SMB_VR_STBY_LVC3_SDA
  SCL  = SMB_VR_STBY_LVC3_SCL
  RESET_N  = NC
  AVRRDY  = VR_VRRDY_PVCCIN_CPU0
  AVREN  = VR_PVCCIN_CPU0_VREN
  VRHOT_N  = IRQ_PVCCIN_CPU0_VRHOT_LVC3_R_N
  PINALRT_N  = FM_PVCCIN_CPU0_PWR_IN_ALERT_N
  MP0  = PWRGD_PVSA_CPU0_R
  MP1  = NC
  VCLK  = SVID_VCLK_PVCCIN_CPU0
  VDIO  = SVID_VDIO_PVCCIN_CPU0
  VALRT_N  = SVID_VALERT_VCCIN_CPU0
  MP2  = PU_VR_PVCCIN_CPU0_FLT1_SMBALT_N
  AVSEN  = VSENSE_PVCCIN_CPU0_AVSP
  AVREF  = VSENSE_PVCCIN_CPU0_N
  AIREF1  = VR_PVCCIN_CPU0_AIREF1
  AISEN1  = ISENSE_PVCCIN_CPU0_PH1_IMON
  AIREF2  = VR_PVCCIN_CPU0_AIREF2
  AISEN2  = ISENSE_PVCCIN_CPU0_PH2_IMON
  AIREF3  = VR_PVCCIN_CPU0_AIREF3
  AISEN3  = ISENSE_PVCCIN_CPU0_PH3_IMON
  AIREF4  = VR_PVCCIN_CPU0_AIREF4
  AISEN4  = ISENSE_PVCCIN_CPU0_PH4_IMON
  AIREF5  = VR_PVCCIN_CPU0_AIREF5
  AISEN5  = ISENSE_PVCCIN_CPU0_PH5_IMON
  AIREF6  = NC
  AISEN6  = NC
  BVSEN  = VSENSE_PVSA_CPU0_BVSP
  BVREF  = VSENSE_PVSA_CPU0_N
  BIREF1  = VR_PVSA_CPU0_BIREF1
  BISEN1  = ISENSE_PVSA_CPU0_IMON
  MP3  = PU_VR_PVCCIN_CPU0_IMON
  MP4  = NC
  XADDR2  = VR_PVCCIN_CPU0_XADDR2
  BTSEN  = A_TSENSE_PVSA_CPU0
  ATSEN  = A_TSENSE_PVCCIN_CPU0
  XADDR1  = VR_PVCCIN_CPU0_XADDR1
  VINSEN  = VR_PVCCIN_CPU0_AVINSEN
  IINSEN  = NC
  VDD  = VR_PVCCIN_CPU0_VDD
  VD12  = VR_PVCCIN_CPU0_VD12
  THPAD  = GND

(kicad_pcb
	(version 20260206)
	(generator "pcbnew")
	(generator_version "10.0")
	(general
		(thickness 1.6)
		(legacy_teardrops no)
	)
	(paper "A4")
	(title_block
		(title "Wiwynn_Tioga_Pass_MB.brd")
		(comment 1 "Tioga Pass / footprint 1893 of 4770 (EU4D4), pads 1-17 of 49")
	)
	(layers
		(0 "F.Cu" signal "TOP")
		(4 "In1.Cu" signal "L2GND")
		(6 "In2.Cu" signal "L3")
		(8 "In3.Cu" signal "L4GND")
		(10 "In4.Cu" signal "L5")
		(12 "In5.Cu" signal "L6GND")
		(14 "In6.Cu" signal "L7VCC")
		(16 "In7.Cu" signal "L8VCC")
		(18 "In8.Cu" signal "L9GND")
		(20 "In9.Cu" signal "L10")
		(22 "In10.Cu" signal "L11GND")
		(24 "In11.Cu" signal "L12")
		(26 "In12.Cu" signal "L13GND")
		(2 "B.Cu" signal "BOTTOM")
		(9 "F.Adhes" user "F.Adhesive")
		(11 "B.Adhes" user "B.Adhesive")
		(13 "F.Paste" user "Package Geometry/Pastemask Top")
		(15 "B.Paste" user "Package Geometry/Pastemask Bottom")
		(5 "F.SilkS" user "Ref Des/Silkscreen Top")
		(7 "B.SilkS" user "Ref Des/Silkscreen Bottom")
		(1 "F.Mask" user "Board Geometry/Soldermask Top")
		(3 "B.Mask" user "Board Geometry/Soldermask Bottom")
		(17 "Dwgs.User" user "User.Drawings")
		(19 "Cmts.User" user "User.Comments")
		(21 "Eco1.User" user "User.Eco1")
		(23 "Eco2.User" user "User.Eco2")
		(25 "Edge.Cuts" user "Board Geometry/Outline")
		(27 "Margin" user)
		(31 "F.CrtYd" user "Package Geometry/Place Bound Top")
		(29 "B.CrtYd" user "Package Geometry/Place Bound Bottom")
		(35 "F.Fab" user "Ref Des/Assembly Top")
		(33 "B.Fab" user "Ref Des/Assembly Bottom")
	)
	(footprint ""
		(layer "F.Cu")
		(at 184.277 -69.85)
		(property "Reference" "EU4D4"
			(at -7.4422 -3.32613 0)
			(unlocked yes)
			(layer "F.SilkS")
			(effects
				(font
					(size 0.7874 0.5842)
					(thickness 0.1524)
				)
				(justify left)
			)
		)
		(property "Value" ""
			(at 0 0 0)
			(layer "F.Fab")
			(effects
				(font
					(size 1.27 1.27)
				)
			)
		)
		(duplicate_pad_numbers_are_jumpers no)
		(pad "1" smd custom
			(at -2.8956 -2.199894)
			(size 0.0508 0.0508)
			(layers "F.Cu" "F.Mask" "F.Paste")
			(net "VR_PVSA_CPU0_PWM")
			(options
				(clearance outline)
				(anchor circle)
			)
			(primitives
				(gr_poly
					(pts
						(arc
							(start 0.254 -0.1016)
							(mid 0.3556 0)
							(end 0.254 0.1016)
						)
						(xy -0.3556 0.1016) (xy -0.3556 -0.1016)
					)
					(width 0)
					(fill yes)
				)
			)
		)
		(pad "2" smd custom
			(at -2.8956 -1.800098)
			(size 0.0508 0.0508)
			(layers "F.Cu" "F.Mask" "F.Paste")
			(net "Net_274")
			(options
				(clearance outline)
				(anchor circle)
			)
			(primitives
				(gr_poly
					(pts
						(arc
							(start 0.254 -0.1016)
							(mid 0.3556 0)
							(end 0.254 0.1016)
						)
						(xy -0.3556 0.1016) (xy -0.3556 -0.1016)
					)
					(width 0)
					(fill yes)
				)
			)
		)
		(pad "3" smd custom
			(at -2.8956 -1.400048)
			(size 0.0508 0.0508)
			(layers "F.Cu" "F.Mask" "F.Paste")
			(net "VR_PVCCIN_CPU0_PWM5")
			(options
				(clearance outline)
				(anchor circle)
			)
			(primitives
				(gr_poly
					(pts
						(arc
							(start 0.254 -0.1016)
							(mid 0.3556 0)
							(end 0.254 0.1016)
						)
						(xy -0.3556 0.1016) (xy -0.3556 -0.1016)
					)
					(width 0)
					(fill yes)
				)
			)
		)
		(pad "4" smd custom
			(at -2.8956 -0.999998)
			(size 0.0508 0.0508)
			(layers "F.Cu" "F.Mask" "F.Paste")
			(net "VR_PVCCIN_CPU0_PWM4")
			(options
				(clearance outline)
				(anchor circle)
			)
			(primitives
				(gr_poly
					(pts
						(arc
							(start 0.254 -0.1016)
							(mid 0.3556 0)
							(end 0.254 0.1016)
						)
						(xy -0.3556 0.1016) (xy -0.3556 -0.1016)
					)
					(width 0)
					(fill yes)
				)
			)
		)
		(pad "5" smd custom
			(at -2.8956 -0.599948)
			(size 0.0508 0.0508)
			(layers "F.Cu" "F.Mask" "F.Paste")
			(net "VR_PVCCIN_CPU0_PWM3")
			(options
				(clearance outline)
				(anchor circle)
			)
			(primitives
				(gr_poly
					(pts
						(arc
							(start 0.254 -0.1016)
							(mid 0.3556 0)
							(end 0.254 0.1016)
						)
						(xy -0.3556 0.1016) (xy -0.3556 -0.1016)
					)
					(width 0)
					(fill yes)
				)
			)
		)
		(pad "6" smd custom
			(at -2.8956 -0.199898)
			(size 0.0508 0.0508)
			(layers "F.Cu" "F.Mask" "F.Paste")
			(net "VR_PVCCIN_CPU0_PWM2")
			(options
				(clearance outline)
				(anchor circle)
			)
			(primitives
				(gr_poly
					(pts
						(arc
							(start 0.254 -0.1016)
							(mid 0.3556 0)
							(end 0.254 0.1016)
						)
						(xy -0.3556 0.1016) (xy -0.3556 -0.1016)
					)
					(width 0)
					(fill yes)
				)
			)
		)
		(pad "7" smd custom
			(at -2.8956 0.199898)
			(size 0.0508 0.0508)
			(layers "F.Cu" "F.Mask" "F.Paste")
			(net "VR_PVCCIN_CPU0_PWM1")
			(options
				(clearance outline)
				(anchor circle)
			)
			(primitives
				(gr_poly
					(pts
						(arc
							(start 0.254 -0.1016)
							(mid 0.3556 0)
							(end 0.254 0.1016)
						)
						(xy -0.3556 0.1016) (xy -0.3556 -0.1016)
					)
					(width 0)
					(fill yes)
				)
			)
		)
		(pad "8" smd custom
			(at -2.8956 0.599948)
			(size 0.0508 0.0508)
			(layers "F.Cu" "F.Mask" "F.Paste")
			(net "SMB_VR_STBY_LVC3_SDA")
			(options
				(clearance outline)
				(anchor circle)
			)
			(primitives
				(gr_poly
					(pts
						(arc
							(start 0.254 -0.1016)
							(mid 0.3556 0)
							(end 0.254 0.1016)
						)
						(xy -0.3556 0.1016) (xy -0.3556 -0.1016)
					)
					(width 0)
					(fill yes)
				)
			)
		)
		(pad "9" smd custom
			(at -2.8956 0.999998)
			(size 0.0508 0.0508)
			(layers "F.Cu" "F.Mask" "F.Paste")
			(net "SMB_VR_STBY_LVC3_SCL")
			(options
				(clearance outline)
				(anchor circle)
			)
			(primitives
				(gr_poly
					(pts
						(arc
							(start 0.254 -0.1016)
							(mid 0.3556 0)
							(end 0.254 0.1016)
						)
						(xy -0.3556 0.1016) (xy -0.3556 -0.1016)
					)
					(width 0)
					(fill yes)
				)
			)
		)
		(pad "10" smd custom
			(at -2.8956 1.400048)
			(size 0.0508 0.0508)
			(layers "F.Cu" "F.Mask" "F.Paste")
			(net "Net_275")
			(options
				(clearance outline)
				(anchor circle)
			)
			(primitives
				(gr_poly
					(pts
						(arc
							(start 0.254 -0.1016)
							(mid 0.3556 0)
							(end 0.254 0.1016)
						)
						(xy -0.3556 0.1016) (xy -0.3556 -0.1016)
					)
					(width 0)
					(fill yes)
				)
			)
		)
		(pad "11" smd custom
			(at -2.8956 1.800098)
			(size 0.0508 0.0508)
			(layers "F.Cu" "F.Mask" "F.Paste")
			(net "VR_VRRDY_PVCCIN_CPU0")
			(options
				(clearance outline)
				(anchor circle)
			)
			(primitives
				(gr_poly
					(pts
						(arc
							(start 0.254 -0.1016)
							(mid 0.3556 0)
							(end 0.254 0.1016)
						)
						(xy -0.3556 0.1016) (xy -0.3556 -0.1016)
					)
					(width 0)
					(fill yes)
				)
			)
		)
		(pad "12" smd custom
			(at -2.8956 2.199894)
			(size 0.0508 0.0508)
			(layers "F.Cu" "F.Mask" "F.Paste")
			(net "VR_PVCCIN_CPU0_VREN")
			(options
				(clearance outline)
				(anchor circle)
			)
			(primitives
				(gr_poly
					(pts
						(arc
							(start 0.254 -0.1016)
							(mid 0.3556 0)
							(end 0.254 0.1016)
						)
						(xy -0.3556 0.1016) (xy -0.3556 -0.1016)
					)
					(width 0)
					(fill yes)
				)
			)
		)
		(pad "13" smd custom
			(at -2.199894 2.8956)
			(size 0.0508 0.0508)
			(layers "F.Cu" "F.Mask" "F.Paste")
			(net "IRQ_PVCCIN_CPU0_VRHOT_LVC3_R_N")
			(options
				(clearance outline)
				(anchor circle)
			)
			(primitives
				(gr_poly
					(pts
						(arc
							(start -0.1016 -0.254)
							(mid 0 -0.3556)
							(end 0.1016 -0.254)
						)
						(xy 0.1016 0.3556) (xy -0.1016 0.3556)
					)
					(width 0)
					(fill yes)
				)
			)
		)
		(pad "14" smd custom
			(at -1.800098 2.8956)
			(size 0.0508 0.0508)
			(layers "F.Cu" "F.Mask" "F.Paste")
			(net "FM_PVCCIN_CPU0_PWR_IN_ALERT_N")
			(options
				(clearance outline)
				(anchor circle)
			)
			(primitives
				(gr_poly
					(pts
						(arc
							(start -0.1016 -0.254)
							(mid 0 -0.3556)
							(end 0.1016 -0.254)
						)
						(xy 0.1016 0.3556) (xy -0.1016 0.3556)
					)
					(width 0)
					(fill yes)
				)
			)
		)
		(pad "15" smd custom
			(at -1.400048 2.8956)
			(size 0.0508 0.0508)
			(layers "F.Cu" "F.Mask" "F.Paste")
			(net "PWRGD_PVSA_CPU0_R")
			(options
				(clearance outline)
				(anchor circle)
			)
			(primitives
				(gr_poly
					(pts
						(arc
							(start -0.1016 -0.254)
							(mid 0 -0.3556)
							(end 0.1016 -0.254)
						)
						(xy 0.1016 0.3556) (xy -0.1016 0.3556)
					)
					(width 0)
					(fill yes)
				)
			)
		)
		(pad "16" smd custom
			(at -0.999998 2.8956)
			(size 0.0508 0.0508)
			(layers "F.Cu" "F.Mask" "F.Paste")
			(net "Net_219")
			(options
				(clearance outline)
				(anchor circle)
			)
			(primitives
				(gr_poly
					(pts
						(arc
							(start -0.1016 -0.254)
							(mid 0 -0.3556)
							(end 0.1016 -0.254)
						)
						(xy 0.1016 0.3556) (xy -0.1016 0.3556)
					)
					(width 0)
					(fill yes)
				)
			)
		)
		(pad "17" smd custom
			(at -0.599948 2.8956)
			(size 0.0508 0.0508)
			(layers "F.Cu" "F.Mask" "F.Paste")
			(net "SVID_VCLK_PVCCIN_CPU0")
			(options
				(clearance outline)
				(anchor circle)
			)
			(primitives
				(gr_poly
					(pts
						(arc
							(start -0.1016 -0.254)
							(mid 0 -0.3556)
							(end 0.1016 -0.254)
						)
						(xy 0.1016 0.3556) (xy -0.1016 0.3556)
					)
					(width 0)
					(fill yes)
				)
			)
		)
	)
)
